FILE_TYPE = CONNECTIVITY;
{Allegro Design Entry HDL 17.2-2016 S066 (3851973) 4/6/2020}
"PAGE_NUMBER" = 5;
0"NC";
1"PRI_EEPROM_SDA";
2"FPGA_OUT_SEC_EEPROM_WP";
3"EEPROM_I2C_SCL";
4"FPGA_OUT_PCA9546_RST_N";
5"PCA9546_I2C_SDA";
6"PCA9546_I2C_SCL";
7"PCIE_SMDAT";
8"PCIE_SMCLK";
9"R_PCA9546_I2C_SDA";
10"R_PCA9546_I2C_SCL";
11"PCA9546_RST_N";
12"UN$5$CONNHDR2X2MSSMT$I126$1";
13"UN$5$CONNHDR2X2MSSMT$I126$3";
14"UN$5$24LC16BTISTTSSOP8$I151$A1";
15"UN$5$24LC16BTISTTSSOP8$I151$A2";
16"BNO080_I2C_SDA";
17"BNO080_I2C_SCL";
18"RGB_LED_I2C_SDA";
19"RGB_LED_I2C_SDA";
20"EEPROM_I2C_SDA";
21"UN$5$PCA9546APWTSSOP16$I33$A0";
22"UN$5$PCA9546APWTSSOP16$I33$A2";
23"UN$5$PCA9546APWTSSOP16$I33$A1";
24"SEC_EEPROM_SDA";
25"PCIE_SMDAT";
26"EEPROM_SCL";
27"VDD_PCA9546A";
28"ICP10100_I2C_SCL";
29"ICP10100_I2C_SDA";
30"SHT3X_I2C_SCL";
31"SHT3X_I2C_SDA";
32"LM75B_I2C_SCL";
33"LM75B_I2C_SDA";
34"EEPROM_SDA";
35"UN$5$24LC16BTISTTSSOP8$I151$A0";
36"RGB_LED_I2C_SCL";
37"RGB_LED_I2C_SCL";
38"SG\g";
39"SG\g";
40"SG\g";
41"XP3R3V_FPGA\g";
42"XP3R3V_FPGA\g";
43"SG\g";
44"XP3R3V_FPGA\g";
45"SG\g";
46"XP3R3V_FPGA\g";
47"XP3R3V_FPGA\g";
48"XP2R5V_FPGA\g";
49"SG\g";
50"XP3R3V_FPGA\g";
51"SG\g";
52"XP3R3V_FPGA\g";
53"FPGA_OUT_SN_EEPROM_WP";
54"SG\g";
55"SEC_EEPROM_WP";
56"SN_EEPROM_WP";
57"EEPROM_SCL";
58"EEPROM_SDA";
59"PCIE_SMCLK";
%"RESISTOR"
"1","(-11000,6100)","0","passive","I100";
;
$LOCATION"R175"
CDS_LOCATION"R175"
$SEC"1"
CDS_SEC"1"
TOLERANCE"1%"
CLS_PN"G155-133R0-01"
CDS_LMAN_SYM_OUTLINE"-50,50,100,-50"
CDS_LIB"passive"
VALUE"33OHM"
PACKAGE"0402"
NO_ASSY"TRUE";
"1"
$PN"1"25;
"2"
$PN"2"58;
%"RESISTOR"
"1","(-11000,5850)","0","passive","I101";
;
$LOCATION"R183"
CDS_LOCATION"R183"
$SEC"1"
CDS_SEC"1"
TOLERANCE"1%"
CLS_PN"G155-133R0-01"
CDS_LIB"passive"
CDS_LMAN_SYM_OUTLINE"-50,50,100,-50"
NO_ASSY"TRUE"
PACKAGE"0402"
VALUE"33OHM";
"1"
$PN"1"20;
"2"
$PN"2"58;
%"RESISTOR"
"1","(-11000,6000)","0","passive","I102";
;
$LOCATION"R176"
CDS_LOCATION"R176"
$SEC"1"
CDS_SEC"1"
TOLERANCE"1%"
CLS_PN"G155-133R0-01"
CDS_LMAN_SYM_OUTLINE"-50,50,100,-50"
CDS_LIB"passive"
PACKAGE"0402"
NO_ASSY"TRUE"
VALUE"33OHM";
"1"
$PN"1"59;
"2"
$PN"2"57;
%"RESISTOR"
"1","(-11000,5750)","0","passive","I103";
;
$LOCATION"R184"
CDS_LOCATION"R184"
$SEC"1"
CDS_SEC"1"
TOLERANCE"1%"
CLS_PN"G155-133R0-01"
CDS_LIB"passive"
CDS_LMAN_SYM_OUTLINE"-50,50,100,-50"
PACKAGE"0402"
NO_ASSY"TRUE"
VALUE"33OHM";
"1"
$PN"1"3;
"2"
$PN"2"57;
%"RESISTOR"
"1","(-11000,6250)","0","passive","I111";
;
$LOCATION"R313"
CDS_LOCATION"R313"
$SEC"1"
CDS_SEC"1"
CLS_PN"G155-100R0-J0"
TOLERANCE"-"
CDS_LIB"passive"
CDS_LMAN_SYM_OUTLINE"-50,50,100,-50"
VALUE"0OHM"
PACKAGE"0402";
"1"
$PN"1"37;
"2"
$PN"2"57;
%"RESISTOR"
"1","(-11000,6350)","0","passive","I112";
;
$LOCATION"R312"
CDS_LOCATION"R312"
$SEC"1"
CDS_SEC"1"
CLS_PN"G155-100R0-J0"
TOLERANCE"-"
CDS_LMAN_SYM_OUTLINE"-50,50,100,-50"
CDS_LIB"passive"
VALUE"0OHM"
PACKAGE"0402";
"1"
$PN"1"19;
"2"
$PN"2"58;
%"RESISTOR"
"1","(-9750,9800)","0","passive","I115";
;
$LOCATION"R311"
CDS_LOCATION"R311"
$SEC"1"
CDS_SEC"1"
CDS_LIB"passive"
CDS_LMAN_SYM_OUTLINE"-50,50,100,-50"
TOLERANCE"-"
CLS_PN"G155-100R0-J0"
PACKAGE"0402"
VALUE"0OHM";
"1"
$PN"1"36;
"2"
$PN"2"10;
%"RESISTOR"
"1","(-9750,9900)","0","passive","I116";
;
$LOCATION"R310"
CDS_LOCATION"R310"
$SEC"1"
CDS_SEC"1"
CDS_LMAN_SYM_OUTLINE"-50,50,100,-50"
CDS_LIB"passive"
TOLERANCE"-"
CLS_PN"G155-100R0-J0"
VALUE"0OHM"
PACKAGE"0402";
"1"
$PN"1"18;
"2"
$PN"2"9;
%"RESISTOR"
"1","(-9750,10800)","0","passive","I125";
;
$LOCATION"R60"
CDS_LOCATION"R60"
$SEC"1"
CDS_SEC"1"
CDS_LIB"passive"
CDS_LMAN_SYM_OUTLINE"-50,50,100,-50"
SIGNAL_MODEL"DEFAULT_RESISTOR_33OHM_2_1"
CLS_PN"G155-133R0-01"
TOLERANCE"1%"
PACKAGE"0402"
VALUE"33OHM";
"1"
$PN"1"4;
"2"
$PN"2"11;
%"CONN_HDR_2X2_M_S_SMT"
"1","(-10150,9450)","2","connector","I126";
;
LOCATION"J9"
$SEC"1"
CDS_SEC"1"
CDS_LIB"connector"
CDS_LMAN_SYM_OUTLINE"0,0,300,-300"
CLS_PN"G200-10686-01"
PART_NUMBER"95278-101A04LF";
"4"
$PN"4"26;
"3"
$PN"3"13;
"2"
$PN"2"34;
"1"
$PN"1"12;
%"CONN_HDR_2X2_M_S_SMT"
"1","(-2450,5650)","0","connector","I127";
;
LOCATION"J17"
$SEC"1"
CDS_SEC"1"
CDS_LMAN_SYM_OUTLINE"0,0,300,-300"
CDS_LIB"connector"
CLS_PN"G200-10686-01"
PART_NUMBER"95278-101A04LF";
"4"
$PN"4"38;
"3"
$PN"3"55;
"2"
$PN"2"38;
"1"
$PN"1"56;
%"GND_SG"
"1","(-1950,5250)","0","cls","I128";
;
VOLTAGE"0"
CDS_LMAN_SYM_OUTLINE"0,0,100,-50"
CDS_LIB"cls"
BODY_TYPE"PLUMBING"
HDL_POWER"SG";
"SGND"38;
%"RESISTOR"
"1","(-11000,5550)","0","passive","I130";
;
$LOCATION"R1"
CDS_LOCATION"R1"
$SEC"1"
CDS_SEC"1"
CDS_LIB"passive"
CDS_LMAN_SYM_OUTLINE"-50,50,100,-50"
TOLERANCE"1%"
CLS_PN"G155-13300-01"
NO_ASSY"TRUE"
PACKAGE"0402"
VALUE"330OHM";
"1"
$PN"1"53;
"2"
$PN"2"56;
%"GND_SG"
"1","(-4250,3850)","0","cls","I139";
;
CDS_LIB"cls"
CDS_LMAN_SYM_OUTLINE"0,0,100,-50"
BODY_TYPE"PLUMBING"
HDL_POWER"SG";
"SGND"39;
%"GND_SG"
"1","(-2400,3700)","0","cls","I147";
;
CDS_LIB"cls"
CDS_LMAN_SYM_OUTLINE"0,0,100,-50"
BODY_TYPE"PLUMBING"
HDL_POWER"SG";
"SGND"40;
%"24LC16BT_I_ST_TSSOP8"
"2","(-2550,4450)","0","memory","I148";
;
$LOCATION"U19"
CDS_LOCATION"U19"
$SEC"2"
CDS_SEC"2"
CDS_LMAN_SYM_OUTLINE"0,0,400,-500"
CDS_LIB"memory"
CLS_PN"G221-10176-01";
"VCC"
$PN"8"44;
"VSS"
$PN"4"40;
%"24LC16BT_I_ST_TSSOP8"
"1","(-5950,4700)","0","memory","I151";
;
$LOCATION"U19"
CDS_LOCATION"U19"
$SEC"1"
CDS_SEC"1"
CDS_LIB"memory"
CDS_LMAN_SYM_OUTLINE"0,0,500,-500"
PART_NUMBER"24LC64T"
CLS_PN"G221-10176-01";
"SDA"
$PN"5"24;
"SCL"
$PN"6"57;
"WP"
$PN"7"55;
"A2"
$PN"3"15;
"A1"
$PN"2"14;
"A0"
$PN"1"35;
%"RESISTOR"
"2","(-5100,4800)","0","passive","I153";
;
$LOCATION"R158"
CDS_LOCATION"R158"
$SEC"1"
CDS_SEC"1"
CDS_LIB"passive"
CDS_LMAN_SYM_OUTLINE"-50,50,50,-100"
TOLERANCE"1%"
CLS_PN"G155-14701-01"
PACKAGE"0402"
VALUE"4.7KOHM";
"1"
$PN"1"41;
"2"
$PN"2"35;
%"RESISTOR"
"2","(-5100,4200)","0","passive","I156";
;
$LOCATION"R159"
CDS_LOCATION"R159"
$SEC"1"
CDS_SEC"1"
CDS_LIB"passive"
CDS_LMAN_SYM_OUTLINE"-50,50,50,-100"
CLS_PN"G155-14701-01"
TOLERANCE"1%"
VALUE"4.7KOHM"
NO_ASSY"TRUE"
PACKAGE"0402";
"1"
$PN"1"35;
"2"
$PN"2"39;
%"VCC"
"1","(-4250,5050)","0","cls","I159";
;
CDS_LIB"cls"
CDS_LMAN_SYM_OUTLINE"-250,250,250,-250"
BODY_TYPE"PLUMBING"
HDL_POWER"XP3R3V_FPGA"
VOLTAGE"3.3V";
"$PIN0"41;
%"RESISTOR"
"2","(-4650,4800)","0","passive","I160";
;
$LOCATION"R160"
CDS_LOCATION"R160"
$SEC"1"
CDS_SEC"1"
CDS_LIB"passive"
CDS_LMAN_SYM_OUTLINE"-50,50,50,-100"
TOLERANCE"1%"
CLS_PN"G155-14701-01"
PACKAGE"0402"
NO_ASSY"TRUE"
VALUE"4.7KOHM";
"1"
$PN"1"41;
"2"
$PN"2"14;
%"RESISTOR"
"2","(-4200,4800)","0","passive","I161";
;
$LOCATION"R162"
CDS_LOCATION"R162"
$SEC"1"
CDS_SEC"1"
TOLERANCE"1%"
CDS_LMAN_SYM_OUTLINE"-50,50,50,-100"
CDS_LIB"passive"
CLS_PN"G155-14701-01"
PACKAGE"0402"
NO_ASSY"TRUE"
VALUE"4.7KOHM";
"1"
$PN"1"41;
"2"
$PN"2"15;
%"RESISTOR"
"1","(-7500,4600)","0","passive","I162";
;
$LOCATION"R45"
CDS_LOCATION"R45"
$SEC"1"
CDS_SEC"1"
CDS_LIB"passive"
CDS_LMAN_SYM_OUTLINE"-50,50,100,-50"
TOLERANCE"1%"
CLS_PN"G155-133R0-01"
VALUE"33OHM"
PACKAGE"0402";
"1"
$PN"1"58;
"2"
$PN"2"24;
%"RESISTOR"
"2","(-4650,4200)","0","passive","I165";
;
$LOCATION"R161"
CDS_LOCATION"R161"
$SEC"1"
CDS_SEC"1"
CLS_PN"G155-14701-01"
TOLERANCE"1%"
CDS_LMAN_SYM_OUTLINE"-50,50,50,-100"
CDS_LIB"passive"
PACKAGE"0402"
VALUE"4.7KOHM";
"1"
$PN"1"14;
"2"
$PN"2"39;
%"RESISTOR"
"2","(-4200,4200)","0","passive","I166";
;
$LOCATION"R163"
CDS_LOCATION"R163"
$SEC"1"
CDS_SEC"1"
CLS_PN"G155-14701-01"
TOLERANCE"1%"
CDS_LMAN_SYM_OUTLINE"-50,50,50,-100"
CDS_LIB"passive"
PACKAGE"0402"
VALUE"4.7KOHM";
"1"
$PN"1"15;
"2"
$PN"2"39;
%"RESISTOR"
"2","(-8850,4000)","0","passive","I167";
;
$LOCATION"R24"
CDS_LOCATION"R24"
$SEC"1"
CDS_SEC"1"
CLS_PN"G155-14701-01"
TOLERANCE"1%"
CDS_LMAN_SYM_OUTLINE"-50,50,50,-100"
CDS_LIB"passive"
VALUE"4.7KOHM"
PACKAGE"0402";
"1"
$PN"1"55;
"2"
$PN"2"43;
%"VCC"
"1","(-8950,4950)","0","cls","I168";
;
CDS_LIB"cls"
CDS_LMAN_SYM_OUTLINE"-250,250,250,-250"
BODY_TYPE"PLUMBING"
HDL_POWER"XP3R3V_FPGA"
VOLTAGE"3.3V";
"$PIN0"42;
%"RESISTOR"
"2","(-8900,4650)","0","passive","I169";
;
$LOCATION"R3"
CDS_LOCATION"R3"
$SEC"1"
CDS_SEC"1"
CLS_PN"G155-14701-01"
TOLERANCE"1%"
CDS_LMAN_SYM_OUTLINE"-50,50,50,-100"
CDS_LIB"passive"
PACKAGE"0402"
VALUE"4.7KOHM"
NO_ASSY"TRUE";
"1"
$PN"1"42;
"2"
$PN"2"55;
%"GND_SG"
"1","(-8900,3600)","0","cls","I170";
;
BODY_TYPE"PLUMBING"
CDS_LMAN_SYM_OUTLINE"0,0,100,-50"
CDS_LIB"cls"
HDL_POWER"SG";
"SGND"43;
%"CAPACITOR"
"2","(-1850,4250)","0","passive","I171";
;
$LOCATION"C1"
CDS_LOCATION"C1"
$SEC"1"
CDS_SEC"1"
TOLERANCE"10%"
CLS_PN"G105-0B104-EK"
CDS_LMAN_SYM_OUTLINE"-50,0,50,-50"
CDS_LIB"passive"
PACKAGE"0402"
VOLTAGE"25V"
VALUE"0.1UF";
"2"
$PN"2"40;
"1"
$PN"1"44;
%"VCC"
"1","(-2400,4700)","0","cls","I172";
;
BODY_TYPE"PLUMBING"
CDS_LMAN_SYM_OUTLINE"-250,250,250,-250"
CDS_LIB"cls"
VOLTAGE"3.3V"
HDL_POWER"XP3R3V_FPGA";
"$PIN0"44;
%"RESISTOR"
"1","(-9750,4300)","0","passive","I173";
;
$LOCATION"R2"
CDS_LOCATION"R2"
$SEC"1"
CDS_SEC"1"
CLS_PN"G155-13300-01"
TOLERANCE"1%"
CDS_LMAN_SYM_OUTLINE"-50,50,100,-50"
CDS_LIB"passive"
PACKAGE"0402"
VALUE"330OHM";
"1"
$PN"1"2;
"2"
$PN"2"55;
%"PCA9546APW_TSSOP16"
"1","(-6550,10900)","0","interface","I33";
;
$LOCATION"U4"
CDS_LOCATION"U4"
$SEC"1"
CDS_SEC"1"
CDS_LIB"interface"
CDS_LMAN_SYM_OUTLINE"0,0,700,-1200"
CLS_PN"G223-10280-01"
PART_NUMBER"TCA9546APWR";
"SDA"
$PN"15"9;
"SCL"
$PN"14"10;
"A2"
$PN"13"22;
"SC3"
$PN"12"17;
"SD3"
$PN"11"16;
"SC2"
$PN"10"28;
"SD2"
$PN"9"29;
"SC1"
$PN"7"30;
"SD1"
$PN"6"31;
"SC0"
$PN"5"32;
"SD0"
$PN"4"33;
"RESET* \B"
$PN"3"11;
"A1"
$PN"2"23;
"A0"
$PN"1"21;
%"RESISTOR"
"1","(-9550,9250)","0","passive","I4";
;
$LOCATION"R59"
CDS_LOCATION"R59"
$SEC"1"
CDS_SEC"1"
SIGNAL_MODEL"DEFAULT_RESISTOR_33OHM_2_1"
CDS_LMAN_SYM_OUTLINE"-50,50,100,-50"
CDS_LIB"passive"
CLS_PN"G155-133R0-01"
TOLERANCE"1%"
PACKAGE"0402"
VALUE"33OHM";
"1"
$PN"1"13;
"2"
$PN"2"10;
%"CAPACITOR"
"2","(-5850,8900)","0","passive","I45";
;
$LOCATION"C38"
CDS_LOCATION"C38"
$SEC"1"
CDS_SEC"1"
TOLERANCE"10%"
CDS_LIB"passive"
CDS_LMAN_SYM_OUTLINE"-50,0,50,-50"
CLS_PN"G105-0B104-CK"
VOLTAGE"10V"
VALUE"0.1UF"
PACKAGE"0402";
"2"
$PN"2"45;
"1"
$PN"1"27;
%"RESISTOR"
"1","(-5150,9350)","0","passive","I52";
;
$LOCATION"R61"
CDS_LOCATION"R61"
$SEC"1"
CDS_SEC"1"
TOLERANCE"-"
CLS_PN"G155-100R0-J0"
CDS_LIB"passive"
CDS_LMAN_SYM_OUTLINE"-50,50,100,-50"
VALUE"0OHM"
PACKAGE"0402"
NO_ASSY"TRUE";
"1"
$PN"1"27;
"2"
$PN"2"48;
%"GND_SG"
"1","(-6300,8300)","0","cls","I53";
;
CDS_LIB"cls"
CDS_LMAN_SYM_OUTLINE"0,0,100,-50"
BODY_TYPE"PLUMBING"
HDL_POWER"SG"
VOLTAGE"0";
"SGND"45;
%"PCA9546APW_TSSOP16"
"2","(-6450,9150)","0","interface","I54";
;
$LOCATION"U4"
CDS_LOCATION"U4"
$SEC"2"
CDS_SEC"2"
CDS_LIB"interface"
CDS_LMAN_SYM_OUTLINE"0,0,400,-500"
CLS_PN"G223-10280-01";
"VDD"
$PN"16"27;
"VSS"
$PN"8"45;
%"RESISTOR"
"2","(-5150,9200)","1","passive","I55";
;
$LOCATION"R62"
CDS_LOCATION"R62"
$SEC"1"
CDS_SEC"1"
TOLERANCE"-"
CLS_PN"G155-100R0-J0"
CDS_LMAN_SYM_OUTLINE"-50,50,50,-100"
CDS_LIB"passive"
VALUE"0OHM"
PACKAGE"0402";
"1"
$PN"1"27;
"2"
$PN"2"46;
%"RESISTOR"
"2","(-8100,11150)","1","passive","I60";
;
$LOCATION"R146"
CDS_LOCATION"R146"
$SEC"1"
CDS_SEC"1"
CDS_LMAN_SYM_OUTLINE"-50,50,50,-100"
CDS_LIB"passive"
TOLERANCE"1%"
CLS_PN"G155-11002-01"
PACKAGE"0402"
VALUE"10KOHM";
"1"
$PN"1"47;
"2"
$PN"2"11;
%"RESISTOR"
"2","(-8100,9350)","1","passive","I66";
;
$LOCATION"R155"
CDS_LOCATION"R155"
$SEC"1"
CDS_SEC"1"
CLS_PN"G155-14701-01"
CDS_LMAN_SYM_OUTLINE"-50,50,50,-100"
CDS_LIB"passive"
TOLERANCE"1%"
VALUE"4.7KOHM"
NO_ASSY"TRUE"
PACKAGE"0402";
"1"
$PN"1"49;
"2"
$PN"2"11;
%"RESISTOR"
"1","(-9750,10400)","0","passive","I67";
;
$LOCATION"R145"
CDS_LOCATION"R145"
$SEC"1"
CDS_SEC"1"
SIGNAL_MODEL"DEFAULT_RESISTOR_33OHM_2_1"
CDS_LMAN_SYM_OUTLINE"-50,50,100,-50"
CDS_LIB"passive"
CLS_PN"G155-133R0-01"
TOLERANCE"1%"
PACKAGE"0402"
VALUE"33OHM";
"1"
$PN"1"6;
"2"
$PN"2"10;
%"RESISTOR"
"1","(-9750,10500)","0","passive","I68";
;
$LOCATION"R144"
CDS_LOCATION"R144"
$SEC"1"
CDS_SEC"1"
SIGNAL_MODEL"DEFAULT_RESISTOR_33OHM_2_1"
CDS_LIB"passive"
CDS_LMAN_SYM_OUTLINE"-50,50,100,-50"
CLS_PN"G155-133R0-01"
TOLERANCE"1%"
PACKAGE"0402"
VALUE"33OHM";
"1"
$PN"1"5;
"2"
$PN"2"9;
%"RESISTOR"
"1","(-9750,10200)","0","passive","I69";
;
$LOCATION"R26"
CDS_LOCATION"R26"
$SEC"1"
CDS_SEC"1"
CDS_LIB"passive"
CDS_LMAN_SYM_OUTLINE"-50,50,100,-50"
CLS_PN"G155-133R0-01"
TOLERANCE"1%"
NO_ASSY"TRUE"
VALUE"33OHM"
PACKAGE"0402";
"1"
$PN"1"7;
"2"
$PN"2"9;
%"RESISTOR"
"1","(-9750,10100)","0","passive","I72";
;
$LOCATION"R27"
CDS_LOCATION"R27"
$SEC"1"
CDS_SEC"1"
CDS_LIB"passive"
CDS_LMAN_SYM_OUTLINE"-50,50,100,-50"
CLS_PN"G155-133R0-01"
TOLERANCE"1%"
NO_ASSY"TRUE"
VALUE"33OHM"
PACKAGE"0402";
"1"
$PN"1"8;
"2"
$PN"2"10;
%"VCC"
"1","(-3800,9450)","0","cls","I76";
;
CDS_LMAN_SYM_OUTLINE"-250,250,250,-250"
CDS_LIB"cls"
BODY_TYPE"PLUMBING"
HDL_POWER"XP3R3V_FPGA"
VOLTAGE"3.3V";
"$PIN0"46;
%"VCC"
"1","(-8700,11300)","0","cls","I77";
;
BODY_TYPE"PLUMBING"
CDS_LIB"cls"
CDS_LMAN_SYM_OUTLINE"-250,250,250,-250"
HDL_POWER"XP3R3V_FPGA"
VOLTAGE"3.3V";
"$PIN0"47;
%"VCC"
"1","(-4450,9450)","0","cls","I78";
;
BODY_TYPE"PLUMBING"
CDS_LMAN_SYM_OUTLINE"-250,250,250,-250"
CDS_LIB"cls"
HDL_POWER"XP2R5V_FPGA"
VOLTAGE"2.5V";
"$PIN0"48;
%"RESISTOR"
"2","(-8100,11050)","1","passive","I80";
;
LOCATION"R147"
$SEC"1"
CDS_SEC"1"
TOLERANCE"1%"
CDS_LIB"passive"
CDS_LMAN_SYM_OUTLINE"-50,50,50,-100"
CLS_PN"G155-11002-01"
VALUE"10KOHM"
PACKAGE"0402";
"1"
$PN"1"47;
"2"
$PN"2"9;
%"RESISTOR"
"2","(-8100,10950)","1","passive","I81";
;
LOCATION"R148"
$SEC"1"
CDS_SEC"1"
TOLERANCE"1%"
CDS_LMAN_SYM_OUTLINE"-50,50,50,-100"
CDS_LIB"passive"
CLS_PN"G155-11002-01"
VALUE"10KOHM"
PACKAGE"0402";
"1"
$PN"1"47;
"2"
$PN"2"10;
%"RESISTOR"
"2","(-8100,10100)","1","passive","I82";
;
LOCATION"R149"
$SEC"1"
CDS_SEC"1"
CDS_LIB"passive"
CDS_LMAN_SYM_OUTLINE"-50,50,50,-100"
CLS_PN"G155-14701-01"
TOLERANCE"1%"
NO_ASSY"TRUE"
VALUE"4.7KOHM"
PACKAGE"0402";
"1"
$PN"1"47;
"2"
$PN"2"21;
%"RESISTOR"
"2","(-8100,10000)","1","passive","I83";
;
LOCATION"R150"
$SEC"1"
CDS_SEC"1"
CDS_LIB"passive"
CDS_LMAN_SYM_OUTLINE"-50,50,50,-100"
CLS_PN"G155-14701-01"
TOLERANCE"1%"
NO_ASSY"TRUE"
VALUE"4.7KOHM"
PACKAGE"0402";
"1"
$PN"1"47;
"2"
$PN"2"23;
%"RESISTOR"
"2","(-8100,9900)","1","passive","I84";
;
LOCATION"R151"
$SEC"1"
CDS_SEC"1"
CDS_LIB"passive"
CDS_LMAN_SYM_OUTLINE"-50,50,50,-100"
CLS_PN"G155-14701-01"
TOLERANCE"1%"
NO_ASSY"TRUE"
VALUE"4.7KOHM"
PACKAGE"0402";
"1"
$PN"1"47;
"2"
$PN"2"22;
%"RESISTOR"
"2","(-8100,9700)","1","passive","I85";
;
LOCATION"R152"
$SEC"1"
CDS_SEC"1"
CDS_LIB"passive"
CDS_LMAN_SYM_OUTLINE"-50,50,50,-100"
CLS_PN"G155-14701-01"
TOLERANCE"1%"
PACKAGE"0402"
VALUE"4.7KOHM";
"1"
$PN"1"49;
"2"
$PN"2"21;
%"RESISTOR"
"2","(-8100,9600)","1","passive","I86";
;
LOCATION"R153"
$SEC"1"
CDS_SEC"1"
CDS_LIB"passive"
CDS_LMAN_SYM_OUTLINE"-50,50,50,-100"
CLS_PN"G155-14701-01"
TOLERANCE"1%"
VALUE"4.7KOHM"
PACKAGE"0402";
"1"
$PN"1"49;
"2"
$PN"2"23;
%"RESISTOR"
"2","(-8100,9500)","1","passive","I87";
;
LOCATION"R154"
$SEC"1"
CDS_SEC"1"
CLS_PN"G155-14701-01"
CDS_LMAN_SYM_OUTLINE"-50,50,50,-100"
CDS_LIB"passive"
TOLERANCE"1%"
PACKAGE"0402"
VALUE"4.7KOHM";
"1"
$PN"1"49;
"2"
$PN"2"22;
%"RESISTOR"
"1","(-9550,9350)","0","passive","I88";
;
LOCATION"R58"
$SEC"1"
CDS_SEC"1"
CDS_LIB"passive"
CDS_LMAN_SYM_OUTLINE"-50,50,100,-50"
SIGNAL_MODEL"DEFAULT_RESISTOR_33OHM_2_1"
CLS_PN"G155-133R0-01"
TOLERANCE"1%"
PACKAGE"0402"
VALUE"33OHM";
"1"
$PN"1"12;
"2"
$PN"2"9;
%"AT24MAC402_SOT23_5"
"1","(-5950,6050)","0","memory","I89";
;
LOCATION"U7"
$SEC"1"
CDS_SEC"1"
CDS_LMAN_SYM_OUTLINE"0,0,500,-400"
CDS_LIB"memory"
VALUE"AT24MAC602-STUM-T"
CLS_PN"A221-00002-FB";
"WP"
$PN"5"56;
"VCC"
$PN"4"50;
"SDA"
$PN"3"1;
"GND"
$PN"2"51;
"SCL"
$PN"1"57;
%"GND_SG"
"1","(-8650,9200)","0","cls","I9";
;
CDS_LMAN_SYM_OUTLINE"0,0,100,-50"
CDS_LIB"cls"
BODY_TYPE"PLUMBING"
HDL_POWER"SG"
VOLTAGE"0";
"SGND"49;
%"RESISTOR"
"1","(-7500,5850)","0","passive","I90";
;
$LOCATION"R345"
CDS_LOCATION"R345"
$SEC"1"
CDS_SEC"1"
TOLERANCE"1%"
CDS_LIB"passive"
CDS_LMAN_SYM_OUTLINE"-50,50,100,-50"
CLS_PN"G155-133R0-01"
PACKAGE"0402"
VALUE"33OHM";
"1"
$PN"1"58;
"2"
$PN"2"1;
%"VCC"
"1","(-4900,6550)","0","cls","I91";
;
CDS_LIB"cls"
CDS_LMAN_SYM_OUTLINE"-250,250,250,-250"
BODY_TYPE"PLUMBING"
VOLTAGE"3.3V"
HDL_POWER"XP3R3V_FPGA";
"$PIN0"50;
%"CAPACITOR"
"2","(-4850,6100)","0","passive","I92";
;
$LOCATION"C225"
CDS_LOCATION"C225"
$SEC"1"
CDS_SEC"1"
TOLERANCE"10%"
CDS_LMAN_SYM_OUTLINE"-50,0,50,-50"
CDS_LIB"passive"
CLS_PN"G105-0B104-EK"
VALUE"0.1UF"
PACKAGE"0402"
VOLTAGE"25V";
"2"
$PN"2"51;
"1"
$PN"1"50;
%"GND_SG"
"1","(-4900,5350)","0","cls","I93";
;
BODY_TYPE"PLUMBING"
CDS_LMAN_SYM_OUTLINE"0,0,100,-50"
CDS_LIB"cls"
HDL_POWER"SG";
"SGND"51;
%"RESISTOR"
"2","(-9700,6300)","0","passive","I94";
;
$LOCATION"R1992"
CDS_LOCATION"R1992"
$SEC"1"
CDS_SEC"1"
CLS_PN"G155-14701-01"
CDS_LIB"passive"
CDS_LMAN_SYM_OUTLINE"-50,50,50,-100"
TOLERANCE"1%"
VALUE"4.7KOHM"
PACKAGE"0402";
"1"
$PN"1"52;
"2"
$PN"2"56;
%"RESISTOR"
"2","(-8900,6300)","0","passive","I95";
;
$LOCATION"R19"
CDS_LOCATION"R19"
$SEC"1"
CDS_SEC"1"
CDS_LMAN_SYM_OUTLINE"-50,50,50,-100"
CDS_LIB"passive"
TOLERANCE"1%"
CLS_PN"G155-11002-01"
PACKAGE"0402"
VALUE"10KOHM";
"1"
$PN"1"52;
"2"
$PN"2"57;
%"RESISTOR"
"2","(-9250,6300)","0","passive","I96";
;
$LOCATION"R1991"
CDS_LOCATION"R1991"
$SEC"1"
CDS_SEC"1"
CDS_LIB"passive"
CDS_LMAN_SYM_OUTLINE"-50,50,50,-100"
TOLERANCE"1%"
CLS_PN"G155-11002-01"
PACKAGE"0402"
VALUE"10KOHM";
"1"
$PN"1"52;
"2"
$PN"2"58;
%"RESISTOR"
"2","(-9750,5300)","0","passive","I97";
;
$LOCATION"R344"
CDS_LOCATION"R344"
$SEC"1"
CDS_SEC"1"
TOLERANCE"1%"
CDS_LMAN_SYM_OUTLINE"-50,50,50,-100"
CDS_LIB"passive"
CLS_PN"G155-14701-01"
NO_ASSY"TRUE"
PACKAGE"0402"
VALUE"4.7KOHM";
"1"
$PN"1"56;
"2"
$PN"2"54;
%"GND_SG"
"1","(-9800,4950)","0","cls","I98";
;
CDS_LIB"cls"
CDS_LMAN_SYM_OUTLINE"0,0,100,-50"
BODY_TYPE"PLUMBING"
HDL_POWER"SG";
"SGND"54;
%"VCC"
"1","(-9750,6750)","0","cls","I99";
;
CDS_LMAN_SYM_OUTLINE"-250,250,250,-250"
CDS_LIB"cls"
BODY_TYPE"PLUMBING"
VOLTAGE"3.3V"
HDL_POWER"XP3R3V_FPGA";
"$PIN0"52;
END.
